(kicad_pcb
	(version 20260206)
	(generator "pcbnew")
	(generator_version "10.0")
	(general
		(thickness 1.6)
		(legacy_teardrops no)
	)
	(paper "A4")
	(title_block
		(title "03242023_DA0F0TMBIJ0_F0T_Motherboard_J_brd_V01_OCP.brd")
		(comment 1 "Grand Teton / footprints 2313-2318 of 6105")
	)
	(layers
		(0 "F.Cu" signal "TOP")
		(4 "In1.Cu" signal "GND")
		(6 "In2.Cu" signal "IN1")
		(8 "In3.Cu" signal "GND1")
		(10 "In4.Cu" signal "IN2")
		(12 "In5.Cu" signal "GND2")
		(14 "In6.Cu" signal "IN3")
		(16 "In7.Cu" signal "GND3")
		(18 "In8.Cu" signal "VCC")
		(20 "In9.Cu" signal "VCC1")
		(22 "In10.Cu" signal "GND4")
		(24 "In11.Cu" signal "IN4")
		(26 "In12.Cu" signal "GND5")
		(28 "In13.Cu" signal "IN5")
		(30 "In14.Cu" signal "GND6")
		(32 "In15.Cu" signal "IN6")
		(34 "In16.Cu" signal "GND7")
		(2 "B.Cu" signal "BOTTOM")
		(9 "F.Adhes" user "F.Adhesive")
		(11 "B.Adhes" user "B.Adhesive")
		(13 "F.Paste" user "Package Geometry/Pastemask Top")
		(15 "B.Paste" user "Package Geometry/Pastemask Bottom")
		(5 "F.SilkS" user "Ref Des/Silkscreen Top")
		(7 "B.SilkS" user "Ref Des/Silkscreen Bottom")
		(1 "F.Mask" user "Board Geometry/Soldermask Top")
		(3 "B.Mask" user "Board Geometry/Soldermask Bottom")
		(17 "Dwgs.User" user "User.Drawings")
		(19 "Cmts.User" user "User.Comments")
		(21 "Eco1.User" user "User.Eco1")
		(23 "Eco2.User" user "User.Eco2")
		(25 "Edge.Cuts" user "Board Geometry/Outline")
		(27 "Margin" user)
		(31 "F.CrtYd" user "Package Geometry/Place Bound Top")
		(29 "B.CrtYd" user "Package Geometry/Place Bound Bottom")
		(35 "F.Fab" user "Ref Des/Assembly Top")
		(33 "B.Fab" user "Ref Des/Assembly Bottom")
	)
	(footprint ""
		(layer "F.Cu")
		(at 273.091656 -129.44983)
		(property "Reference" "C2337"
			(at 0 0 0)
			(layer "F.SilkS")
			(hide yes)
			(effects
				(font
					(size 1.27 1.27)
				)
			)
		)
		(property "Value" ""
			(at 0 0 0)
			(layer "F.Fab")
			(effects
				(font
					(size 1.27 1.27)
				)
			)
		)
		(duplicate_pad_numbers_are_jumpers no)
		(fp_line
			(start -0.7874 -0.4064)
			(end 0.7874 -0.4064)
			(stroke
				(width 0.1524)
				(type default)
			)
			(layer "F.SilkS")
		)
		(fp_line
			(start -0.7874 0.4064)
			(end -0.7874 -0.4064)
			(stroke
				(width 0.1524)
				(type default)
			)
			(layer "F.SilkS")
		)
		(fp_line
			(start 0.7874 -0.4064)
			(end 0.7874 0.4064)
			(stroke
				(width 0.1524)
				(type default)
			)
			(layer "F.SilkS")
		)
		(fp_line
			(start 0.7874 0.4064)
			(end -0.7874 0.4064)
			(stroke
				(width 0.1524)
				(type default)
			)
			(layer "F.SilkS")
		)
		(fp_line
			(start -0.67945 -0.305054)
			(end -0.12065 -0.305054)
			(stroke
				(width 0.1)
				(type default)
			)
			(layer "F.Fab")
		)
		(fp_line
			(start -0.67945 0.3048)
			(end -0.67945 -0.305054)
			(stroke
				(width 0.1)
				(type default)
			)
			(layer "F.Fab")
		)
		(fp_line
			(start -0.12065 -0.305054)
			(end -0.12065 -0.2794)
			(stroke
				(width 0.1)
				(type default)
			)
			(layer "F.Fab")
		)
		(fp_line
			(start -0.12065 -0.2794)
			(end 0.12065 -0.2794)
			(stroke
				(width 0.1)
				(type default)
			)
			(layer "F.Fab")
		)
		(fp_line
			(start -0.12065 0.2794)
			(end -0.12065 0.3048)
			(stroke
				(width 0.1)
				(type default)
			)
			(layer "F.Fab")
		)
		(fp_line
			(start -0.12065 0.3048)
			(end -0.67945 0.3048)
			(stroke
				(width 0.1)
				(type default)
			)
			(layer "F.Fab")
		)
		(fp_line
			(start 0.120396 0.2794)
			(end -0.12065 0.2794)
			(stroke
				(width 0.1)
				(type default)
			)
			(layer "F.Fab")
		)
		(fp_line
			(start 0.120396 0.3048)
			(end 0.120396 0.2794)
			(stroke
				(width 0.1)
				(type default)
			)
			(layer "F.Fab")
		)
		(fp_line
			(start 0.12065 -0.3048)
			(end 0.67945 -0.3048)
			(stroke
				(width 0.1)
				(type default)
			)
			(layer "F.Fab")
		)
		(fp_line
			(start 0.12065 -0.2794)
			(end 0.12065 -0.3048)
			(stroke
				(width 0.1)
				(type default)
			)
			(layer "F.Fab")
		)
		(fp_line
			(start 0.67945 -0.3048)
			(end 0.67945 0.3048)
			(stroke
				(width 0.1)
				(type default)
			)
			(layer "F.Fab")
		)
		(fp_line
			(start 0.67945 0.3048)
			(end 0.120396 0.3048)
			(stroke
				(width 0.1)
				(type default)
			)
			(layer "F.Fab")
		)
		(pad "1" smd circle
			(at -0.40005 0)
			(size 0 0)
			(layers "F.Cu" "F.Mask" "F.Paste")
			(net "P3V3_AUX")
		)
		(pad "2" smd circle
			(at 0.40005 0)
			(size 0 0)
			(layers "F.Cu" "F.Mask" "F.Paste")
			(net "GND")
		)
	)
	(footprint ""
		(layer "F.Cu")
		(at 97.338896 -344.029284 90)
		(property "Reference" "PC579"
			(at 0 0 90)
			(layer "F.SilkS")
			(hide yes)
			(effects
				(font
					(size 1.27 1.27)
				)
			)
		)
		(property "Value" ""
			(at 0 0 90)
			(layer "F.Fab")
			(effects
				(font
					(size 1.27 1.27)
				)
			)
		)
		(duplicate_pad_numbers_are_jumpers no)
		(fp_line
			(start -3.400044 1.249934)
			(end 3.400044 1.249934)
			(stroke
				(width 0.1524)
				(type default)
			)
			(layer "F.SilkS")
		)
		(fp_circle
			(center 0 1.249934)
			(end 0 4.649978)
			(stroke
				(width 0.1524)
				(type default)
			)
			(fill no)
			(layer "F.SilkS")
		)
		(fp_poly
			(pts
				(arc
					(start -3.400044 1.249934)
					(mid 0 4.649978)
					(end 3.400044 1.249934)
				)
			)
			(stroke
				(width 0)
				(type default)
			)
			(fill yes)
			(layer "F.SilkS")
		)
		(fp_circle
			(center 0 1.249934)
			(end 0 4.649978)
			(stroke
				(width 0.1)
				(type default)
			)
			(fill no)
			(layer "F.Fab")
		)
		(pad "1" thru_hole rect
			(at 0 0 90)
			(size 1.524 1.524)
			(drill 1.016)
			(layers "*.Cu" "*.Mask")
			(remove_unused_layers no)
			(net "SW_P12V_PVCCIN_CPU1_FLT")
			(clearance 0)
			(padstack
				(mode front_inner_back)
				(layer "Inner"
					(shape circle)
					(size 1.524 1.524)
					(clearance 0)
				)
				(layer "B.Cu"
					(shape rect)
					(size 1.524 1.524)
					(clearance 0)
				)
			)
		)
		(pad "2" thru_hole circle
			(at 0 2.500122 90)
			(size 1.524 1.524)
			(drill 1.016)
			(layers "*.Cu" "*.Mask")
			(remove_unused_layers no)
			(net "GND")
			(clearance 0)
		)
	)
	(footprint ""
		(layer "F.Cu")
		(at 104.3432 -251.375672 90)
		(property "Reference" "C256"
			(at 0 0 90)
			(layer "F.SilkS")
			(hide yes)
			(effects
				(font
					(size 1.27 1.27)
				)
			)
		)
		(property "Value" ""
			(at 0 0 90)
			(layer "F.Fab")
			(effects
				(font
					(size 1.27 1.27)
				)
			)
		)
		(duplicate_pad_numbers_are_jumpers no)
		(fp_line
			(start 0.7874 -0.4064)
			(end 0.7874 0.4064)
			(stroke
				(width 0.1524)
				(type default)
			)
			(layer "F.SilkS")
		)
		(fp_line
			(start -0.7874 -0.4064)
			(end 0.7874 -0.4064)
			(stroke
				(width 0.1524)
				(type default)
			)
			(layer "F.SilkS")
		)
		(fp_line
			(start 0.7874 0.4064)
			(end -0.7874 0.4064)
			(stroke
				(width 0.1524)
				(type default)
			)
			(layer "F.SilkS")
		)
		(fp_line
			(start -0.7874 0.4064)
			(end -0.7874 -0.4064)
			(stroke
				(width 0.1524)
				(type default)
			)
			(layer "F.SilkS")
		)
		(fp_line
			(start -0.12065 -0.305054)
			(end -0.12065 -0.2794)
			(stroke
				(width 0.1)
				(type default)
			)
			(layer "F.Fab")
		)
		(fp_line
			(start -0.67945 -0.305054)
			(end -0.12065 -0.305054)
			(stroke
				(width 0.1)
				(type default)
			)
			(layer "F.Fab")
		)
		(fp_line
			(start 0.67945 -0.3048)
			(end 0.67945 0.3048)
			(stroke
				(width 0.1)
				(type default)
			)
			(layer "F.Fab")
		)
		(fp_line
			(start 0.12065 -0.3048)
			(end 0.67945 -0.3048)
			(stroke
				(width 0.1)
				(type default)
			)
			(layer "F.Fab")
		)
		(fp_line
			(start 0.12065 -0.2794)
			(end 0.12065 -0.3048)
			(stroke
				(width 0.1)
				(type default)
			)
			(layer "F.Fab")
		)
		(fp_line
			(start -0.12065 -0.2794)
			(end 0.12065 -0.2794)
			(stroke
				(width 0.1)
				(type default)
			)
			(layer "F.Fab")
		)
		(fp_line
			(start 0.120396 0.2794)
			(end -0.12065 0.2794)
			(stroke
				(width 0.1)
				(type default)
			)
			(layer "F.Fab")
		)
		(fp_line
			(start -0.12065 0.2794)
			(end -0.12065 0.3048)
			(stroke
				(width 0.1)
				(type default)
			)
			(layer "F.Fab")
		)
		(fp_line
			(start 0.67945 0.3048)
			(end 0.120396 0.3048)
			(stroke
				(width 0.1)
				(type default)
			)
			(layer "F.Fab")
		)
		(fp_line
			(start 0.120396 0.3048)
			(end 0.120396 0.2794)
			(stroke
				(width 0.1)
				(type default)
			)
			(layer "F.Fab")
		)
		(fp_line
			(start -0.12065 0.3048)
			(end -0.67945 0.3048)
			(stroke
				(width 0.1)
				(type default)
			)
			(layer "F.Fab")
		)
		(fp_line
			(start -0.67945 0.3048)
			(end -0.67945 -0.305054)
			(stroke
				(width 0.1)
				(type default)
			)
			(layer "F.Fab")
		)
		(pad "1" smd circle
			(at -0.40005 0 90)
			(size 0 0)
			(layers "F.Cu" "F.Mask" "F.Paste")
			(net "PVCCIN_CPU1")
		)
		(pad "2" smd circle
			(at 0.40005 0 90)
			(size 0 0)
			(layers "F.Cu" "F.Mask" "F.Paste")
			(net "GND")
		)
	)
	(footprint ""
		(layer "F.Cu")
		(at 141.240256 -65.329308)
		(property "Reference" "R2350"
			(at 0 0 0)
			(layer "F.SilkS")
			(hide yes)
			(effects
				(font
					(size 1.27 1.27)
				)
			)
		)
		(property "Value" ""
			(at 0 0 0)
			(layer "F.Fab")
			(effects
				(font
					(size 1.27 1.27)
				)
			)
		)
		(duplicate_pad_numbers_are_jumpers no)
		(fp_line
			(start -0.7874 -0.4064)
			(end 0.7874 -0.4064)
			(stroke
				(width 0.1524)
				(type default)
			)
			(layer "F.SilkS")
		)
		(fp_line
			(start -0.7874 0.4064)
			(end -0.7874 -0.4064)
			(stroke
				(width 0.1524)
				(type default)
			)
			(layer "F.SilkS")
		)
		(fp_line
			(start 0.7874 -0.4064)
			(end 0.7874 0.4064)
			(stroke
				(width 0.1524)
				(type default)
			)
			(layer "F.SilkS")
		)
		(fp_line
			(start 0.7874 0.4064)
			(end -0.7874 0.4064)
			(stroke
				(width 0.1524)
				(type default)
			)
			(layer "F.SilkS")
		)
		(fp_line
			(start -0.67945 -0.305054)
			(end -0.12065 -0.305054)
			(stroke
				(width 0.1)
				(type default)
			)
			(layer "F.Fab")
		)
		(fp_line
			(start -0.67945 0.3048)
			(end -0.67945 -0.305054)
			(stroke
				(width 0.1)
				(type default)
			)
			(layer "F.Fab")
		)
		(fp_line
			(start -0.12065 -0.305054)
			(end -0.12065 -0.2794)
			(stroke
				(width 0.1)
				(type default)
			)
			(layer "F.Fab")
		)
		(fp_line
			(start -0.12065 -0.2794)
			(end 0.12065 -0.2794)
			(stroke
				(width 0.1)
				(type default)
			)
			(layer "F.Fab")
		)
		(fp_line
			(start -0.12065 0.2794)
			(end -0.12065 0.3048)
			(stroke
				(width 0.1)
				(type default)
			)
			(layer "F.Fab")
		)
		(fp_line
			(start -0.12065 0.3048)
			(end -0.67945 0.3048)
			(stroke
				(width 0.1)
				(type default)
			)
			(layer "F.Fab")
		)
		(fp_line
			(start 0.120396 0.2794)
			(end -0.12065 0.2794)
			(stroke
				(width 0.1)
				(type default)
			)
			(layer "F.Fab")
		)
		(fp_line
			(start 0.120396 0.3048)
			(end 0.120396 0.2794)
			(stroke
				(width 0.1)
				(type default)
			)
			(layer "F.Fab")
		)
		(fp_line
			(start 0.12065 -0.3048)
			(end 0.67945 -0.3048)
			(stroke
				(width 0.1)
				(type default)
			)
			(layer "F.Fab")
		)
		(fp_line
			(start 0.12065 -0.2794)
			(end 0.12065 -0.3048)
			(stroke
				(width 0.1)
				(type default)
			)
			(layer "F.Fab")
		)
		(fp_line
			(start 0.67945 -0.3048)
			(end 0.67945 0.3048)
			(stroke
				(width 0.1)
				(type default)
			)
			(layer "F.Fab")
		)
		(fp_line
			(start 0.67945 0.3048)
			(end 0.120396 0.3048)
			(stroke
				(width 0.1)
				(type default)
			)
			(layer "F.Fab")
		)
		(pad "1" smd circle
			(at -0.40005 0)
			(size 0 0)
			(layers "F.Cu" "F.Mask" "F.Paste")
			(net "FM_PS_EN_PLD_BUF1")
		)
		(pad "2" smd circle
			(at 0.40005 0)
			(size 0 0)
			(layers "F.Cu" "F.Mask" "F.Paste")
			(net "FM_PS_EN_PLD_BUF1_R1")
		)
	)
	(footprint ""
		(layer "F.Cu")
		(at 50.43551 -165.808914 180)
		(property "Reference" "PR1804"
			(at 0 0 180)
			(layer "F.SilkS")
			(hide yes)
			(effects
				(font
					(size 1.27 1.27)
				)
			)
		)
		(property "Value" ""
			(at 0 0 180)
			(layer "F.Fab")
			(effects
				(font
					(size 1.27 1.27)
				)
			)
		)
		(duplicate_pad_numbers_are_jumpers no)
		(fp_line
			(start 0.7874 0.4064)
			(end -0.7874 0.4064)
			(stroke
				(width 0.1524)
				(type default)
			)
			(layer "F.SilkS")
		)
		(fp_line
			(start 0.7874 -0.4064)
			(end 0.7874 0.4064)
			(stroke
				(width 0.1524)
				(type default)
			)
			(layer "F.SilkS")
		)
		(fp_line
			(start -0.7874 0.4064)
			(end -0.7874 -0.4064)
			(stroke
				(width 0.1524)
				(type default)
			)
			(layer "F.SilkS")
		)
		(fp_line
			(start -0.7874 -0.4064)
			(end 0.7874 -0.4064)
			(stroke
				(width 0.1524)
				(type default)
			)
			(layer "F.SilkS")
		)
		(fp_line
			(start 0.67945 0.3048)
			(end 0.120396 0.3048)
			(stroke
				(width 0.1)
				(type default)
			)
			(layer "F.Fab")
		)
		(fp_line
			(start 0.67945 -0.3048)
			(end 0.67945 0.3048)
			(stroke
				(width 0.1)
				(type default)
			)
			(layer "F.Fab")
		)
		(fp_line
			(start 0.12065 -0.2794)
			(end 0.12065 -0.3048)
			(stroke
				(width 0.1)
				(type default)
			)
			(layer "F.Fab")
		)
		(fp_line
			(start 0.12065 -0.3048)
			(end 0.67945 -0.3048)
			(stroke
				(width 0.1)
				(type default)
			)
			(layer "F.Fab")
		)
		(fp_line
			(start 0.120396 0.3048)
			(end 0.120396 0.2794)
			(stroke
				(width 0.1)
				(type default)
			)
			(layer "F.Fab")
		)
		(fp_line
			(start 0.120396 0.2794)
			(end -0.12065 0.2794)
			(stroke
				(width 0.1)
				(type default)
			)
			(layer "F.Fab")
		)
		(fp_line
			(start -0.12065 0.3048)
			(end -0.67945 0.3048)
			(stroke
				(width 0.1)
				(type default)
			)
			(layer "F.Fab")
		)
		(fp_line
			(start -0.12065 0.2794)
			(end -0.12065 0.3048)
			(stroke
				(width 0.1)
				(type default)
			)
			(layer "F.Fab")
		)
		(fp_line
			(start -0.12065 -0.2794)
			(end 0.12065 -0.2794)
			(stroke
				(width 0.1)
				(type default)
			)
			(layer "F.Fab")
		)
		(fp_line
			(start -0.12065 -0.305054)
			(end -0.12065 -0.2794)
			(stroke
				(width 0.1)
				(type default)
			)
			(layer "F.Fab")
		)
		(fp_line
			(start -0.67945 0.3048)
			(end -0.67945 -0.305054)
			(stroke
				(width 0.1)
				(type default)
			)
			(layer "F.Fab")
		)
		(fp_line
			(start -0.67945 -0.305054)
			(end -0.12065 -0.305054)
			(stroke
				(width 0.1)
				(type default)
			)
			(layer "F.Fab")
		)
		(pad "1" smd circle
			(at -0.40005 0 180)
			(size 0 0)
			(layers "F.Cu" "F.Mask" "F.Paste")
			(net "SW_PVCCD_HV_CPU1_BOOT1")
		)
		(pad "2" smd circle
			(at 0.40005 0 180)
			(size 0 0)
			(layers "F.Cu" "F.Mask" "F.Paste")
			(net "SW_PVCCD_HV_CPU1_BOOT1_R")
		)
	)
	(footprint ""
		(layer "F.Cu")
		(at 378.349256 -92.887292 -90)
		(property "Reference" "R3056"
			(at 0 0 270)
			(layer "F.SilkS")
			(hide yes)
			(effects
				(font
					(size 1.27 1.27)
				)
			)
		)
		(property "Value" ""
			(at 0 0 270)
			(layer "F.Fab")
			(effects
				(font
					(size 1.27 1.27)
				)
			)
		)
		(duplicate_pad_numbers_are_jumpers no)
		(fp_line
			(start -0.7874 0.4064)
			(end -0.7874 -0.4064)
			(stroke
				(width 0.1524)
				(type default)
			)
			(layer "F.SilkS")
		)
		(fp_line
			(start 0.7874 0.4064)
			(end -0.7874 0.4064)
			(stroke
				(width 0.1524)
				(type default)
			)
			(layer "F.SilkS")
		)
		(fp_line
			(start -0.7874 -0.4064)
			(end 0.7874 -0.4064)
			(stroke
				(width 0.1524)
				(type default)
			)
			(layer "F.SilkS")
		)
		(fp_line
			(start 0.7874 -0.4064)
			(end 0.7874 0.4064)
			(stroke
				(width 0.1524)
				(type default)
			)
			(layer "F.SilkS")
		)
		(fp_line
			(start -0.67945 0.3048)
			(end -0.67945 -0.305054)
			(stroke
				(width 0.1)
				(type default)
			)
			(layer "F.Fab")
		)
		(fp_line
			(start -0.12065 0.3048)
			(end -0.67945 0.3048)
			(stroke
				(width 0.1)
				(type default)
			)
			(layer "F.Fab")
		)
		(fp_line
			(start 0.120396 0.3048)
			(end 0.120396 0.2794)
			(stroke
				(width 0.1)
				(type default)
			)
			(layer "F.Fab")
		)
		(fp_line
			(start 0.67945 0.3048)
			(end 0.120396 0.3048)
			(stroke
				(width 0.1)
				(type default)
			)
			(layer "F.Fab")
		)
		(fp_line
			(start -0.12065 0.2794)
			(end -0.12065 0.3048)
			(stroke
				(width 0.1)
				(type default)
			)
			(layer "F.Fab")
		)
		(fp_line
			(start 0.120396 0.2794)
			(end -0.12065 0.2794)
			(stroke
				(width 0.1)
				(type default)
			)
			(layer "F.Fab")
		)
		(fp_line
			(start -0.12065 -0.2794)
			(end 0.12065 -0.2794)
			(stroke
				(width 0.1)
				(type default)
			)
			(layer "F.Fab")
		)
		(fp_line
			(start 0.12065 -0.2794)
			(end 0.12065 -0.3048)
			(stroke
				(width 0.1)
				(type default)
			)
			(layer "F.Fab")
		)
		(fp_line
			(start 0.12065 -0.3048)
			(end 0.67945 -0.3048)
			(stroke
				(width 0.1)
				(type default)
			)
			(layer "F.Fab")
		)
		(fp_line
			(start 0.67945 -0.3048)
			(end 0.67945 0.3048)
			(stroke
				(width 0.1)
				(type default)
			)
			(layer "F.Fab")
		)
		(fp_line
			(start -0.67945 -0.305054)
			(end -0.12065 -0.305054)
			(stroke
				(width 0.1)
				(type default)
			)
			(layer "F.Fab")
		)
		(fp_line
			(start -0.12065 -0.305054)
			(end -0.12065 -0.2794)
			(stroke
				(width 0.1)
				(type default)
			)
			(layer "F.Fab")
		)
		(pad "1" smd circle
			(at -0.40005 0 270)
			(size 0 0)
			(layers "F.Cu" "F.Mask" "F.Paste")
			(net "JTAG_DBP_BMC_PRDY_R1_N")
		)
		(pad "2" smd circle
			(at 0.40005 0 270)
			(size 0 0)
			(layers "F.Cu" "F.Mask" "F.Paste")
			(net "JTAG_DBP_BMC_PRDY_N")
		)
	)
)
